FILE_TYPE = CONNECTIVITY;
{Allegro Design Entry HDL 17.2-2016 S081 (4005846) 1/11/2022}
"PAGE_NUMBER" = 275;
0"NC";
1"P5E_CPU0_G3_TX_DN<15:0>";
2"P5E_CPU0_G3_TX_DP<15:0>";
3"P5E_CPU0_G3_TX_C_DN<15:0>";
4"P5E_CPU0_G3_TX_C_DP<15:0>";
5"P5E_CPU0_G3_TX_DN<14>";
6"P5E_CPU0_G3_TX_DP<14>";
7"P5E_CPU0_G3_TX_DN<12>";
8"P5E_CPU0_G3_TX_DP<13>";
9"P5E_CPU0_G3_TX_C_DP<11>";
10"P5E_CPU0_G3_TX_C_DN<10>";
11"P5E_CPU0_G3_TX_C_DP<10>";
12"P5E_CPU0_G3_TX_C_DN<9>";
13"P5E_CPU0_G3_TX_C_DP<9>";
14"P5E_CPU0_G3_TX_C_DN<8>";
15"P5E_CPU0_G3_TX_C_DP<8>";
16"P5E_CPU0_G3_TX_C_DN<7>";
17"P5E_CPU0_G3_TX_C_DP<7>";
18"P5E_CPU0_G3_TX_C_DN<6>";
19"P5E_CPU0_G3_TX_C_DP<6>";
20"P5E_CPU0_G3_TX_C_DN<5>";
21"P5E_CPU0_G3_TX_C_DP<5>";
22"P5E_CPU0_G3_TX_C_DN<4>";
23"P5E_CPU0_G3_TX_C_DP<4>";
24"P5E_CPU0_G3_TX_C_DN<3>";
25"P5E_CPU0_G3_TX_DN<1>";
26"P5E_CPU0_G3_TX_C_DN<15>";
27"P5E_CPU0_G3_TX_C_DP<15>";
28"P5E_CPU0_G3_TX_DP<15>";
29"P5E_CPU0_G3_TX_C_DN<14>";
30"P5E_CPU0_G3_TX_C_DP<14>";
31"P5E_CPU0_G3_TX_C_DN<13>";
32"P5E_CPU0_G3_TX_C_DP<13>";
33"P5E_CPU0_G3_TX_C_DN<12>";
34"P5E_CPU0_G3_TX_C_DP<12>";
35"P5E_CPU0_G3_TX_DN<13>";
36"P5E_CPU0_G3_TX_C_DN<11>";
37"P5E_CPU0_G3_TX_DN<11>";
38"P5E_CPU0_G3_TX_DN<8>";
39"P5E_CPU0_G3_TX_DP<12>";
40"P5E_CPU0_G3_TX_DP<11>";
41"P5E_CPU0_G3_TX_DP<5>";
42"P5E_CPU0_G3_TX_DN<4>";
43"P5E_CPU0_G3_TX_DN<3>";
44"P5E_CPU0_G3_TX_DP<10>";
45"P5E_CPU0_G3_TX_DP<6>";
46"P5E_CPU0_G3_TX_DN<10>";
47"P5E_CPU0_G3_TX_C_DN<2>";
48"P5E_CPU0_G3_TX_C_DN<1>";
49"P5E_CPU0_G3_TX_C_DN<0>";
50"P5E_CPU0_G3_TX_C_DP<0>";
51"P5E_CPU0_G3_TX_C_DP<1>";
52"P5E_CPU0_G3_TX_C_DP<3>";
53"P5E_CPU0_G3_TX_DN<9>";
54"P5E_CPU0_G3_TX_DP<8>";
55"P5E_CPU0_G3_TX_DN<7>";
56"P5E_CPU0_G3_TX_DP<7>";
57"P5E_CPU0_G3_TX_C_DP<2>";
58"P5E_CPU0_G3_TX_DP<1>";
59"P5E_CPU0_G3_TX_DN<2>";
60"P5E_CPU0_G3_TX_DP<9>";
61"P5E_CPU0_G3_TX_DP<4>";
62"P5E_CPU0_G3_TX_DP<2>";
63"P5E_CPU0_G3_TX_DN<6>";
64"P5E_CPU0_G3_TX_DN<5>";
65"P5E_CPU0_G3_TX_DN<0>";
66"P5E_CPU0_G3_TX_DP<0>";
67"P5E_CPU0_G3_TX_DP<3>";
68"P5E_CPU0_G3_TX_DN<15>";
%"TAP"
"6","(-6375,4175)","0","standard","I1";
;
CDS_LIB"standard"
HDL_TAP"TRUE"
BODY_TYPE"PLUMBING";
"B \NAC \NWC"1;
"S \NAC"
BN"15"68;
%"TAP"
"6","(-6375,4475)","0","standard","I10";
;
CDS_LIB"standard"
HDL_TAP"TRUE"
BODY_TYPE"PLUMBING";
"B \NAC \NWC"1;
"S \NAC"
BN"12"7;
%"Q_CAP_DIFFBUS"
"2","(-5500,5725)","0","pure_quanta","I101";
;
LOCATION"C461"
$SEC"1"
CDS_SEC"1"
PACK_TYPE"C0201"
VALUE"DIFF BUS_0.22UF"
MATERIAL"X6S"
TOLERANCE"20%"
PART_NUMBER"SP_CH4221MEE01"
VOLTAGE"6.3V"
CDS_LMAN_SYM_OUTLINE"-25,50,25,-50"
PIN_NAMES_ROTATE"True"
CDS_LIB"pure_quanta";
"2"
$PN"2"50;
"1"
$PN"1"66;
%"Q_CAP_DIFFBUS"
"2","(-5500,5675)","2","pure_quanta","I102";
;
LOCATION"C462"
SEC"1"
VALUE"DIFF BUS_0.22UF"
VOLTAGE"6.3V"
TOLERANCE"20%"
PART_NUMBER"SP_CH4221MEE01"
MATERIAL"X6S"
CDS_LIB"pure_quanta"
CDS_LMAN_SYM_OUTLINE"-25,50,25,-50"
PIN_NAMES_ROTATE"True"
SEC_TYPE"C0201"
PACK_TYPE"C0201";
"2"
$PN"2"65;
"1"
$PN"1"49;
%"Q_CAP_DIFFBUS"
"2","(-5500,5625)","2","pure_quanta","I103";
;
LOCATION"C463"
$SEC"1"
CDS_SEC"1"
VALUE"DIFF BUS_0.22UF"
VOLTAGE"6.3V"
TOLERANCE"20%"
PART_NUMBER"SP_CH4221MEE01"
MATERIAL"X6S"
PIN_NAMES_ROTATE"True"
PACK_TYPE"C0201"
CDS_LMAN_SYM_OUTLINE"-25,50,25,-50"
CDS_LIB"pure_quanta";
"2"
$PN"2"58;
"1"
$PN"1"51;
%"Q_CAP_DIFFBUS"
"2","(-5500,5525)","2","pure_quanta","I104";
;
LOCATION"C465"
$SEC"1"
CDS_SEC"1"
VALUE"DIFF BUS_0.22UF"
PACK_TYPE"C0201"
PIN_NAMES_ROTATE"True"
MATERIAL"X6S"
PART_NUMBER"SP_CH4221MEE01"
TOLERANCE"20%"
VOLTAGE"6.3V"
CDS_LMAN_SYM_OUTLINE"-25,50,25,-50"
CDS_LIB"pure_quanta";
"2"
$PN"2"62;
"1"
$PN"1"57;
%"Q_CAP_DIFFBUS"
"2","(-5500,5575)","2","pure_quanta","I105";
;
LOCATION"C464"
$SEC"1"
CDS_SEC"1"
VALUE"DIFF BUS_0.22UF"
VOLTAGE"6.3V"
TOLERANCE"20%"
PART_NUMBER"SP_CH4221MEE01"
MATERIAL"X6S"
PIN_NAMES_ROTATE"True"
PACK_TYPE"C0201"
CDS_LMAN_SYM_OUTLINE"-25,50,25,-50"
CDS_LIB"pure_quanta";
"2"
$PN"2"25;
"1"
$PN"1"48;
%"Q_CAP_DIFFBUS"
"2","(-5500,5375)","2","pure_quanta","I106";
;
LOCATION"C468"
$SEC"1"
CDS_SEC"1"
VALUE"DIFF BUS_0.22UF"
CDS_LIB"pure_quanta"
CDS_LMAN_SYM_OUTLINE"-25,50,25,-50"
VOLTAGE"6.3V"
TOLERANCE"20%"
PART_NUMBER"SP_CH4221MEE01"
MATERIAL"X6S"
PIN_NAMES_ROTATE"True"
PACK_TYPE"C0201";
"2"
$PN"2"43;
"1"
$PN"1"24;
%"Q_CAP_DIFFBUS"
"2","(-5500,5475)","2","pure_quanta","I107";
;
LOCATION"C466"
$SEC"1"
CDS_SEC"1"
VALUE"DIFF BUS_0.22UF"
CDS_LIB"pure_quanta"
CDS_LMAN_SYM_OUTLINE"-25,50,25,-50"
VOLTAGE"6.3V"
TOLERANCE"20%"
PART_NUMBER"SP_CH4221MEE01"
MATERIAL"X6S"
PIN_NAMES_ROTATE"True"
PACK_TYPE"C0201";
"2"
$PN"2"59;
"1"
$PN"1"47;
%"Q_CAP_DIFFBUS"
"2","(-5500,5425)","2","pure_quanta","I108";
;
LOCATION"C467"
$SEC"1"
CDS_SEC"1"
VALUE"DIFF BUS_0.22UF"
CDS_LIB"pure_quanta"
CDS_LMAN_SYM_OUTLINE"-25,50,25,-50"
VOLTAGE"6.3V"
TOLERANCE"20%"
PART_NUMBER"SP_CH4221MEE01"
MATERIAL"X6S"
PIN_NAMES_ROTATE"True"
PACK_TYPE"C0201";
"2"
$PN"2"67;
"1"
$PN"1"52;
%"Q_CAP_DIFFBUS"
"2","(-5500,5325)","2","pure_quanta","I109";
;
LOCATION"C469"
$SEC"1"
CDS_SEC"1"
VALUE"DIFF BUS_0.22UF"
CDS_LIB"pure_quanta"
CDS_LMAN_SYM_OUTLINE"-25,50,25,-50"
PACK_TYPE"C0201"
PIN_NAMES_ROTATE"True"
MATERIAL"X6S"
PART_NUMBER"SP_CH4221MEE01"
TOLERANCE"20%"
VOLTAGE"6.3V";
"2"
$PN"2"61;
"1"
$PN"1"23;
%"TAP"
"6","(-6375,4375)","0","standard","I11";
;
CDS_LIB"standard"
HDL_TAP"TRUE"
BODY_TYPE"PLUMBING";
"B \NAC \NWC"1;
"S \NAC"
BN"13"35;
%"Q_CAP_DIFFBUS"
"2","(-5500,5275)","2","pure_quanta","I110";
;
LOCATION"C470"
$SEC"1"
CDS_SEC"1"
VALUE"DIFF BUS_0.22UF"
PACK_TYPE"C0201"
PIN_NAMES_ROTATE"True"
MATERIAL"X6S"
PART_NUMBER"SP_CH4221MEE01"
TOLERANCE"20%"
VOLTAGE"6.3V"
CDS_LMAN_SYM_OUTLINE"-25,50,25,-50"
CDS_LIB"pure_quanta";
"2"
$PN"2"42;
"1"
$PN"1"22;
%"Q_CAP_DIFFBUS"
"2","(-5500,5225)","2","pure_quanta","I111";
;
LOCATION"C471"
$SEC"1"
CDS_SEC"1"
VALUE"DIFF BUS_0.22UF"
CDS_LIB"pure_quanta"
CDS_LMAN_SYM_OUTLINE"-25,50,25,-50"
VOLTAGE"6.3V"
TOLERANCE"20%"
PART_NUMBER"SP_CH4221MEE01"
MATERIAL"X6S"
PIN_NAMES_ROTATE"True"
PACK_TYPE"C0201";
"2"
$PN"2"41;
"1"
$PN"1"21;
%"Q_CAP_DIFFBUS"
"2","(-5500,5125)","2","pure_quanta","I112";
;
LOCATION"C473"
$SEC"1"
CDS_SEC"1"
VALUE"DIFF BUS_0.22UF"
PACK_TYPE"C0201"
PIN_NAMES_ROTATE"True"
MATERIAL"X6S"
PART_NUMBER"SP_CH4221MEE01"
TOLERANCE"20%"
VOLTAGE"6.3V"
CDS_LMAN_SYM_OUTLINE"-25,50,25,-50"
CDS_LIB"pure_quanta";
"2"
$PN"2"45;
"1"
$PN"1"19;
%"Q_CAP_DIFFBUS"
"2","(-5500,5175)","2","pure_quanta","I113";
;
LOCATION"C472"
$SEC"1"
CDS_SEC"1"
VALUE"DIFF BUS_0.22UF"
PACK_TYPE"C0201"
PIN_NAMES_ROTATE"True"
MATERIAL"X6S"
PART_NUMBER"SP_CH4221MEE01"
TOLERANCE"20%"
VOLTAGE"6.3V"
CDS_LMAN_SYM_OUTLINE"-25,50,25,-50"
CDS_LIB"pure_quanta";
"2"
$PN"2"64;
"1"
$PN"1"20;
%"Q_CAP_DIFFBUS"
"2","(-5500,5075)","2","pure_quanta","I114";
;
LOCATION"C474"
$SEC"1"
CDS_SEC"1"
VALUE"DIFF BUS_0.22UF"
CDS_LIB"pure_quanta"
CDS_LMAN_SYM_OUTLINE"-25,50,25,-50"
PACK_TYPE"C0201"
PIN_NAMES_ROTATE"True"
MATERIAL"X6S"
PART_NUMBER"SP_CH4221MEE01"
TOLERANCE"20%"
VOLTAGE"6.3V";
"2"
$PN"2"63;
"1"
$PN"1"18;
%"Q_CAP_DIFFBUS"
"2","(-5500,5025)","2","pure_quanta","I115";
;
LOCATION"C475"
$SEC"1"
CDS_SEC"1"
VALUE"DIFF BUS_0.22UF"
PACK_TYPE"C0201"
PIN_NAMES_ROTATE"True"
MATERIAL"X6S"
PART_NUMBER"SP_CH4221MEE01"
TOLERANCE"20%"
VOLTAGE"6.3V"
CDS_LMAN_SYM_OUTLINE"-25,50,25,-50"
CDS_LIB"pure_quanta";
"2"
$PN"2"56;
"1"
$PN"1"17;
%"Q_CAP_DIFFBUS"
"2","(-5500,4975)","2","pure_quanta","I116";
;
LOCATION"C476"
$SEC"1"
CDS_SEC"1"
VALUE"DIFF BUS_0.22UF"
PACK_TYPE"C0201"
PIN_NAMES_ROTATE"True"
MATERIAL"X6S"
PART_NUMBER"SP_CH4221MEE01"
TOLERANCE"20%"
VOLTAGE"6.3V"
CDS_LMAN_SYM_OUTLINE"-25,50,25,-50"
CDS_LIB"pure_quanta";
"2"
$PN"2"55;
"1"
$PN"1"16;
%"Q_CAP_DIFFBUS"
"2","(-5500,4925)","2","pure_quanta","I117";
;
LOCATION"C477"
$SEC"1"
CDS_SEC"1"
VALUE"DIFF BUS_0.22UF"
CDS_LIB"pure_quanta"
CDS_LMAN_SYM_OUTLINE"-25,50,25,-50"
PACK_TYPE"C0201"
PIN_NAMES_ROTATE"True"
MATERIAL"X6S"
PART_NUMBER"SP_CH4221MEE01"
TOLERANCE"20%"
VOLTAGE"6.3V";
"2"
$PN"2"54;
"1"
$PN"1"15;
%"Q_CAP_DIFFBUS"
"2","(-5500,4875)","2","pure_quanta","I118";
;
LOCATION"C478"
$SEC"1"
CDS_SEC"1"
VALUE"DIFF BUS_0.22UF"
CDS_LIB"pure_quanta"
CDS_LMAN_SYM_OUTLINE"-25,50,25,-50"
VOLTAGE"6.3V"
TOLERANCE"20%"
PART_NUMBER"SP_CH4221MEE01"
MATERIAL"X6S"
PIN_NAMES_ROTATE"True"
PACK_TYPE"C0201";
"2"
$PN"2"38;
"1"
$PN"1"14;
%"Q_CAP_DIFFBUS"
"2","(-5500,4825)","2","pure_quanta","I119";
;
LOCATION"C479"
$SEC"1"
CDS_SEC"1"
VALUE"DIFF BUS_0.22UF"
PACK_TYPE"C0201"
PIN_NAMES_ROTATE"True"
MATERIAL"X6S"
PART_NUMBER"SP_CH4221MEE01"
TOLERANCE"20%"
VOLTAGE"6.3V"
CDS_LMAN_SYM_OUTLINE"-25,50,25,-50"
CDS_LIB"pure_quanta";
"2"
$PN"2"60;
"1"
$PN"1"13;
%"TAP"
"6","(-6225,4325)","0","standard","I12";
;
CDS_LIB"standard"
HDL_TAP"TRUE"
BODY_TYPE"PLUMBING";
"B \NAC \NWC"2;
"S \NAC"
BN"14"6;
%"Q_CAP_DIFFBUS"
"2","(-5500,4775)","2","pure_quanta","I120";
;
LOCATION"C480"
$SEC"1"
CDS_SEC"1"
VALUE"DIFF BUS_0.22UF"
PACK_TYPE"C0201"
PIN_NAMES_ROTATE"True"
MATERIAL"X6S"
PART_NUMBER"SP_CH4221MEE01"
TOLERANCE"20%"
VOLTAGE"6.3V"
CDS_LMAN_SYM_OUTLINE"-25,50,25,-50"
CDS_LIB"pure_quanta";
"2"
$PN"2"53;
"1"
$PN"1"12;
%"Q_CAP_DIFFBUS"
"2","(-5500,4725)","2","pure_quanta","I121";
;
LOCATION"C481"
$SEC"1"
CDS_SEC"1"
VALUE"DIFF BUS_0.22UF"
CDS_LIB"pure_quanta"
CDS_LMAN_SYM_OUTLINE"-25,50,25,-50"
PACK_TYPE"C0201"
PIN_NAMES_ROTATE"True"
MATERIAL"X6S"
PART_NUMBER"SP_CH4221MEE01"
TOLERANCE"20%"
VOLTAGE"6.3V";
"2"
$PN"2"44;
"1"
$PN"1"11;
%"Q_CAP_DIFFBUS"
"2","(-5500,4675)","2","pure_quanta","I122";
;
LOCATION"C482"
$SEC"1"
CDS_SEC"1"
VALUE"DIFF BUS_0.22UF"
CDS_LIB"pure_quanta"
CDS_LMAN_SYM_OUTLINE"-25,50,25,-50"
VOLTAGE"6.3V"
TOLERANCE"20%"
PART_NUMBER"SP_CH4221MEE01"
MATERIAL"X6S"
PIN_NAMES_ROTATE"True"
PACK_TYPE"C0201";
"2"
$PN"2"46;
"1"
$PN"1"10;
%"Q_CAP_DIFFBUS"
"2","(-5500,4625)","2","pure_quanta","I123";
;
LOCATION"C483"
$SEC"1"
CDS_SEC"1"
VALUE"DIFF BUS_0.22UF"
PACK_TYPE"C0201"
PIN_NAMES_ROTATE"True"
MATERIAL"X6S"
PART_NUMBER"SP_CH4221MEE01"
TOLERANCE"20%"
VOLTAGE"6.3V"
CDS_LMAN_SYM_OUTLINE"-25,50,25,-50"
CDS_LIB"pure_quanta";
"2"
$PN"2"40;
"1"
$PN"1"9;
%"Q_CAP_DIFFBUS"
"2","(-5500,4575)","2","pure_quanta","I124";
;
LOCATION"C484"
$SEC"1"
CDS_SEC"1"
VALUE"DIFF BUS_0.22UF"
PACK_TYPE"C0201"
PIN_NAMES_ROTATE"True"
MATERIAL"X6S"
PART_NUMBER"SP_CH4221MEE01"
TOLERANCE"20%"
VOLTAGE"6.3V"
CDS_LMAN_SYM_OUTLINE"-25,50,25,-50"
CDS_LIB"pure_quanta";
"2"
$PN"2"37;
"1"
$PN"1"36;
%"Q_CAP_DIFFBUS"
"2","(-5500,4525)","2","pure_quanta","I125";
;
LOCATION"C485"
$SEC"1"
CDS_SEC"1"
VALUE"DIFF BUS_0.22UF"
PACK_TYPE"C0201"
PIN_NAMES_ROTATE"True"
MATERIAL"X6S"
PART_NUMBER"SP_CH4221MEE01"
TOLERANCE"20%"
VOLTAGE"6.3V"
CDS_LMAN_SYM_OUTLINE"-25,50,25,-50"
CDS_LIB"pure_quanta";
"2"
$PN"2"39;
"1"
$PN"1"34;
%"Q_CAP_DIFFBUS"
"2","(-5500,4475)","2","pure_quanta","I126";
;
LOCATION"C486"
$SEC"1"
CDS_SEC"1"
VALUE"DIFF BUS_0.22UF"
PACK_TYPE"C0201"
PIN_NAMES_ROTATE"True"
MATERIAL"X6S"
PART_NUMBER"SP_CH4221MEE01"
TOLERANCE"20%"
VOLTAGE"6.3V"
CDS_LMAN_SYM_OUTLINE"-25,50,25,-50"
CDS_LIB"pure_quanta";
"2"
$PN"2"7;
"1"
$PN"1"33;
%"Q_CAP_DIFFBUS"
"2","(-5500,4425)","2","pure_quanta","I127";
;
LOCATION"C487"
$SEC"1"
CDS_SEC"1"
VALUE"DIFF BUS_0.22UF"
PACK_TYPE"C0201"
PIN_NAMES_ROTATE"True"
MATERIAL"X6S"
PART_NUMBER"SP_CH4221MEE01"
TOLERANCE"20%"
VOLTAGE"6.3V"
CDS_LMAN_SYM_OUTLINE"-25,50,25,-50"
CDS_LIB"pure_quanta";
"2"
$PN"2"8;
"1"
$PN"1"32;
%"Q_CAP_DIFFBUS"
"2","(-5500,4375)","2","pure_quanta","I128";
;
LOCATION"C488"
$SEC"1"
CDS_SEC"1"
VALUE"DIFF BUS_0.22UF"
PACK_TYPE"C0201"
PIN_NAMES_ROTATE"True"
MATERIAL"X6S"
PART_NUMBER"SP_CH4221MEE01"
TOLERANCE"20%"
VOLTAGE"6.3V"
CDS_LMAN_SYM_OUTLINE"-25,50,25,-50"
CDS_LIB"pure_quanta";
"2"
$PN"2"35;
"1"
$PN"1"31;
%"Q_CAP_DIFFBUS"
"2","(-5500,4325)","2","pure_quanta","I129";
;
LOCATION"C489"
$SEC"1"
CDS_SEC"1"
VALUE"DIFF BUS_0.22UF"
CDS_LIB"pure_quanta"
CDS_LMAN_SYM_OUTLINE"-25,50,25,-50"
VOLTAGE"6.3V"
TOLERANCE"20%"
PART_NUMBER"SP_CH4221MEE01"
MATERIAL"X6S"
PIN_NAMES_ROTATE"True"
PACK_TYPE"C0201";
"2"
$PN"2"6;
"1"
$PN"1"30;
%"TAP"
"6","(-6225,4425)","0","standard","I13";
;
CDS_LIB"standard"
HDL_TAP"TRUE"
BODY_TYPE"PLUMBING";
"B \NAC \NWC"2;
"S \NAC"
BN"13"8;
%"Q_CAP_DIFFBUS"
"2","(-5500,4275)","2","pure_quanta","I130";
;
LOCATION"C490"
$SEC"1"
CDS_SEC"1"
VALUE"DIFF BUS_0.22UF"
CDS_LIB"pure_quanta"
CDS_LMAN_SYM_OUTLINE"-25,50,25,-50"
VOLTAGE"6.3V"
TOLERANCE"20%"
PART_NUMBER"SP_CH4221MEE01"
MATERIAL"X6S"
PIN_NAMES_ROTATE"True"
PACK_TYPE"C0201";
"2"
$PN"2"5;
"1"
$PN"1"29;
%"Q_CAP_DIFFBUS"
"2","(-5500,4225)","2","pure_quanta","I131";
;
LOCATION"C491"
$SEC"1"
CDS_SEC"1"
VALUE"DIFF BUS_0.22UF"
CDS_LIB"pure_quanta"
CDS_LMAN_SYM_OUTLINE"-25,50,25,-50"
VOLTAGE"6.3V"
TOLERANCE"20%"
PART_NUMBER"SP_CH4221MEE01"
MATERIAL"X6S"
PIN_NAMES_ROTATE"True"
PACK_TYPE"C0201";
"2"
$PN"2"28;
"1"
$PN"1"27;
%"Q_CAP_DIFFBUS"
"2","(-5500,4175)","2","pure_quanta","I132";
;
LOCATION"C492"
$SEC"1"
CDS_SEC"1"
VALUE"DIFF BUS_0.22UF"
CDS_LIB"pure_quanta"
CDS_LMAN_SYM_OUTLINE"-25,50,25,-50"
VOLTAGE"6.3V"
TOLERANCE"20%"
PART_NUMBER"SP_CH4221MEE01"
MATERIAL"X6S"
PIN_NAMES_ROTATE"True"
PACK_TYPE"C0201";
"2"
$PN"2"68;
"1"
$PN"1"26;
%"TAP"
"6","(-6375,4575)","0","standard","I14";
;
CDS_LIB"standard"
HDL_TAP"TRUE"
BODY_TYPE"PLUMBING";
"B \NAC \NWC"1;
"S \NAC"
BN"11"37;
%"TAP"
"6","(-6375,4675)","0","standard","I15";
;
CDS_LIB"standard"
HDL_TAP"TRUE"
BODY_TYPE"PLUMBING";
"B \NAC \NWC"1;
"S \NAC"
BN"10"46;
%"TAP"
"6","(-6225,4625)","0","standard","I16";
;
CDS_LIB"standard"
HDL_TAP"TRUE"
BODY_TYPE"PLUMBING";
"B \NAC \NWC"2;
"S \NAC"
BN"11"40;
%"TAP"
"6","(-6225,4525)","0","standard","I17";
;
CDS_LIB"standard"
HDL_TAP"TRUE"
BODY_TYPE"PLUMBING";
"B \NAC \NWC"2;
"S \NAC"
BN"12"39;
%"TAP"
"6","(-6225,4725)","0","standard","I18";
;
CDS_LIB"standard"
HDL_TAP"TRUE"
BODY_TYPE"PLUMBING";
"B \NAC \NWC"2;
"S \NAC"
BN"10"44;
%"TAP"
"6","(-6375,4775)","0","standard","I19";
;
CDS_LIB"standard"
HDL_TAP"TRUE"
BODY_TYPE"PLUMBING";
"B \NAC \NWC"1;
"S \NAC"
BN"9"53;
%"TAP"
"6","(-6225,4225)","0","standard","I2";
;
CDS_LIB"standard"
HDL_TAP"TRUE"
BODY_TYPE"PLUMBING";
"B \NAC \NWC"2;
"S \NAC"
BN"15"28;
%"TAP"
"6","(-6375,4875)","0","standard","I20";
;
CDS_LIB"standard"
HDL_TAP"TRUE"
BODY_TYPE"PLUMBING";
"B \NAC \NWC"1;
"S \NAC"
BN"8"38;
%"TAP"
"6","(-6375,4975)","0","standard","I21";
;
CDS_LIB"standard"
HDL_TAP"TRUE"
BODY_TYPE"PLUMBING";
"B \NAC \NWC"1;
"S \NAC"
BN"7"55;
%"TAP"
"6","(-6225,4825)","0","standard","I22";
;
CDS_LIB"standard"
HDL_TAP"TRUE"
BODY_TYPE"PLUMBING";
"B \NAC \NWC"2;
"S \NAC"
BN"9"60;
%"TAP"
"6","(-6225,4925)","0","standard","I23";
;
CDS_LIB"standard"
HDL_TAP"TRUE"
BODY_TYPE"PLUMBING";
"B \NAC \NWC"2;
"S \NAC"
BN"8"54;
%"TAP"
"6","(-6375,5075)","0","standard","I24";
;
CDS_LIB"standard"
HDL_TAP"TRUE"
BODY_TYPE"PLUMBING";
"B \NAC \NWC"1;
"S \NAC"
BN"6"63;
%"TAP"
"6","(-6375,5175)","0","standard","I25";
;
CDS_LIB"standard"
HDL_TAP"TRUE"
BODY_TYPE"PLUMBING";
"B \NAC \NWC"1;
"S \NAC"
BN"5"64;
%"TAP"
"6","(-6225,5125)","0","standard","I26";
;
CDS_LIB"standard"
HDL_TAP"TRUE"
BODY_TYPE"PLUMBING";
"B \NAC \NWC"2;
"S \NAC"
BN"6"45;
%"TAP"
"6","(-6225,5025)","0","standard","I27";
;
CDS_LIB"standard"
HDL_TAP"TRUE"
BODY_TYPE"PLUMBING";
"B \NAC \NWC"2;
"S \NAC"
BN"7"56;
%"TAP"
"6","(-6225,5225)","0","standard","I28";
;
CDS_LIB"standard"
HDL_TAP"TRUE"
BODY_TYPE"PLUMBING";
"B \NAC \NWC"2;
"S \NAC"
BN"5"41;
%"TAP"
"6","(-6375,5375)","0","standard","I49";
;
CDS_LIB"standard"
HDL_TAP"TRUE"
BODY_TYPE"PLUMBING";
"B \NAC \NWC"1;
"S \NAC"
BN"3"43;
%"TAP"
"6","(-4500,4225)","2","standard","I5";
;
CDS_LIB"standard"
BOM_COST"IO_SLOT"
BODY_TYPE"PLUMBING"
HDL_TAP"TRUE"
ROOM"RISER1";
"B \NAC \NWC"4;
"S \NAC"
BN"15"27;
%"TAP"
"6","(-6375,5275)","0","standard","I50";
;
CDS_LIB"standard"
HDL_TAP"TRUE"
BODY_TYPE"PLUMBING";
"B \NAC \NWC"1;
"S \NAC"
BN"4"42;
%"TAP"
"6","(-6375,5475)","0","standard","I51";
;
CDS_LIB"standard"
HDL_TAP"TRUE"
BODY_TYPE"PLUMBING";
"B \NAC \NWC"1;
"S \NAC"
BN"2"59;
%"TAP"
"6","(-6225,5325)","0","standard","I52";
;
CDS_LIB"standard"
HDL_TAP"TRUE"
BODY_TYPE"PLUMBING";
"B \NAC \NWC"2;
"S \NAC"
BN"4"61;
%"TAP"
"6","(-6225,5525)","0","standard","I53";
;
CDS_LIB"standard"
HDL_TAP"TRUE"
BODY_TYPE"PLUMBING";
"B \NAC \NWC"2;
"S \NAC"
BN"2"62;
%"TAP"
"6","(-6225,5425)","0","standard","I54";
;
CDS_LIB"standard"
HDL_TAP"TRUE"
BODY_TYPE"PLUMBING";
"B \NAC \NWC"2;
"S \NAC"
BN"3"67;
%"TAP"
"6","(-6375,5575)","0","standard","I55";
;
CDS_LIB"standard"
HDL_TAP"TRUE"
BODY_TYPE"PLUMBING";
"B \NAC \NWC"1;
"S \NAC"
BN"1"25;
%"TAP"
"6","(-6375,5675)","0","standard","I56";
;
CDS_LIB"standard"
HDL_TAP"TRUE"
BODY_TYPE"PLUMBING";
"B \NAC \NWC"1;
"S \NAC"
BN"0"65;
%"TAP"
"6","(-6225,5625)","0","standard","I57";
;
CDS_LIB"standard"
HDL_TAP"TRUE"
BODY_TYPE"PLUMBING";
"B \NAC \NWC"2;
"S \NAC"
BN"1"58;
%"TAP"
"6","(-6225,5725)","0","standard","I58";
;
CDS_LIB"standard"
HDL_TAP"TRUE"
BODY_TYPE"PLUMBING";
"B \NAC \NWC"2;
"S \NAC"
BN"0"66;
%"TAP"
"6","(-4500,4425)","2","standard","I68";
;
CDS_LIB"standard"
BOM_COST"IO_SLOT"
BODY_TYPE"PLUMBING"
HDL_TAP"TRUE"
ROOM"RISER1";
"B \NAC \NWC"4;
"S \NAC"
BN"13"32;
%"TAP"
"6","(-4500,4325)","2","standard","I69";
;
CDS_LIB"standard"
BOM_COST"IO_SLOT"
BODY_TYPE"PLUMBING"
HDL_TAP"TRUE"
ROOM"RISER1";
"B \NAC \NWC"4;
"S \NAC"
BN"14"30;
%"TAP"
"6","(-4500,4625)","2","standard","I70";
;
CDS_LIB"standard"
BOM_COST"IO_SLOT"
BODY_TYPE"PLUMBING"
HDL_TAP"TRUE"
ROOM"RISER1";
"B \NAC \NWC"4;
"S \NAC"
BN"11"9;
%"TAP"
"6","(-4500,4725)","2","standard","I71";
;
CDS_LIB"standard"
BOM_COST"IO_SLOT"
BODY_TYPE"PLUMBING"
HDL_TAP"TRUE"
ROOM"RISER1";
"B \NAC \NWC"4;
"S \NAC"
BN"10"11;
%"TAP"
"6","(-4500,4525)","2","standard","I72";
;
CDS_LIB"standard"
BOM_COST"IO_SLOT"
BODY_TYPE"PLUMBING"
HDL_TAP"TRUE"
ROOM"RISER1";
"B \NAC \NWC"4;
"S \NAC"
BN"12"34;
%"TAP"
"6","(-4500,4925)","2","standard","I73";
;
CDS_LIB"standard"
BOM_COST"IO_SLOT"
BODY_TYPE"PLUMBING"
HDL_TAP"TRUE"
ROOM"RISER1";
"B \NAC \NWC"4;
"S \NAC"
BN"8"15;
%"TAP"
"6","(-4500,4825)","2","standard","I74";
;
CDS_LIB"standard"
BOM_COST"IO_SLOT"
BODY_TYPE"PLUMBING"
HDL_TAP"TRUE"
ROOM"RISER1";
"B \NAC \NWC"4;
"S \NAC"
BN"9"13;
%"TAP"
"6","(-4500,5125)","2","standard","I75";
;
CDS_LIB"standard"
BOM_COST"IO_SLOT"
BODY_TYPE"PLUMBING"
HDL_TAP"TRUE"
ROOM"RISER1";
"B \NAC \NWC"4;
"S \NAC"
BN"6"19;
%"TAP"
"6","(-4500,5225)","2","standard","I76";
;
CDS_LIB"standard"
BOM_COST"IO_SLOT"
BODY_TYPE"PLUMBING"
HDL_TAP"TRUE"
ROOM"RISER1";
"B \NAC \NWC"4;
"S \NAC"
BN"5"21;
%"TAP"
"6","(-4500,5025)","2","standard","I77";
;
CDS_LIB"standard"
BOM_COST"IO_SLOT"
BODY_TYPE"PLUMBING"
HDL_TAP"TRUE"
ROOM"RISER1";
"B \NAC \NWC"4;
"S \NAC"
BN"7"17;
%"TAP"
"6","(-4500,5525)","2","standard","I78";
;
CDS_LIB"standard"
BOM_COST"IO_SLOT"
BODY_TYPE"PLUMBING"
HDL_TAP"TRUE"
ROOM"RISER1";
"B \NAC \NWC"4;
"S \NAC"
BN"2"57;
%"TAP"
"6","(-4500,5325)","2","standard","I79";
;
CDS_LIB"standard"
BOM_COST"IO_SLOT"
BODY_TYPE"PLUMBING"
HDL_TAP"TRUE"
ROOM"RISER1";
"B \NAC \NWC"4;
"S \NAC"
BN"4"23;
%"TAP"
"6","(-4500,5425)","2","standard","I80";
;
CDS_LIB"standard"
BOM_COST"IO_SLOT"
BODY_TYPE"PLUMBING"
HDL_TAP"TRUE"
ROOM"RISER1";
"B \NAC \NWC"4;
"S \NAC"
BN"3"52;
%"TAP"
"6","(-4500,5725)","2","standard","I81";
;
CDS_LIB"standard"
BOM_COST"IO_SLOT"
BODY_TYPE"PLUMBING"
HDL_TAP"TRUE"
ROOM"RISER1";
"B \NAC \NWC"4;
"S \NAC"
BN"0"50;
%"TAP"
"6","(-4500,5625)","2","standard","I82";
;
CDS_LIB"standard"
BOM_COST"IO_SLOT"
BODY_TYPE"PLUMBING"
HDL_TAP"TRUE"
ROOM"RISER1";
"B \NAC \NWC"4;
"S \NAC"
BN"1"51;
%"TAP"
"6","(-4350,4175)","2","standard","I83";
;
CDS_LIB"standard"
BOM_COST"IO_SLOT"
BODY_TYPE"PLUMBING"
HDL_TAP"TRUE"
ROOM"RISER1";
"B \NAC \NWC"3;
"S \NAC"
BN"15"26;
%"TAP"
"6","(-4350,4275)","2","standard","I84";
;
CDS_LIB"standard"
BOM_COST"IO_SLOT"
BODY_TYPE"PLUMBING"
HDL_TAP"TRUE"
ROOM"RISER1";
"B \NAC \NWC"3;
"S \NAC"
BN"14"29;
%"TAP"
"6","(-4350,4375)","2","standard","I85";
;
CDS_LIB"standard"
BOM_COST"IO_SLOT"
BODY_TYPE"PLUMBING"
HDL_TAP"TRUE"
ROOM"RISER1";
"B \NAC \NWC"3;
"S \NAC"
BN"13"31;
%"TAP"
"6","(-4350,4475)","2","standard","I86";
;
CDS_LIB"standard"
BOM_COST"IO_SLOT"
BODY_TYPE"PLUMBING"
HDL_TAP"TRUE"
ROOM"RISER1";
"B \NAC \NWC"3;
"S \NAC"
BN"12"33;
%"TAP"
"6","(-4350,4575)","2","standard","I87";
;
CDS_LIB"standard"
BOM_COST"IO_SLOT"
BODY_TYPE"PLUMBING"
HDL_TAP"TRUE"
ROOM"RISER1";
"B \NAC \NWC"3;
"S \NAC"
BN"11"36;
%"TAP"
"6","(-4350,4675)","2","standard","I88";
;
CDS_LIB"standard"
BOM_COST"IO_SLOT"
BODY_TYPE"PLUMBING"
HDL_TAP"TRUE"
ROOM"RISER1";
"B \NAC \NWC"3;
"S \NAC"
BN"10"10;
%"TAP"
"6","(-4350,4875)","2","standard","I89";
;
CDS_LIB"standard"
BOM_COST"IO_SLOT"
BODY_TYPE"PLUMBING"
HDL_TAP"TRUE"
ROOM"RISER1";
"B \NAC \NWC"3;
"S \NAC"
BN"8"14;
%"TAP"
"6","(-6375,4275)","0","standard","I9";
;
CDS_LIB"standard"
HDL_TAP"TRUE"
BODY_TYPE"PLUMBING";
"B \NAC \NWC"1;
"S \NAC"
BN"14"5;
%"TAP"
"6","(-4350,4775)","2","standard","I90";
;
CDS_LIB"standard"
BOM_COST"IO_SLOT"
BODY_TYPE"PLUMBING"
HDL_TAP"TRUE"
ROOM"RISER1";
"B \NAC \NWC"3;
"S \NAC"
BN"9"12;
%"TAP"
"6","(-4350,4975)","2","standard","I91";
;
CDS_LIB"standard"
BOM_COST"IO_SLOT"
BODY_TYPE"PLUMBING"
HDL_TAP"TRUE"
ROOM"RISER1";
"B \NAC \NWC"3;
"S \NAC"
BN"7"16;
%"TAP"
"6","(-4350,5075)","2","standard","I92";
;
CDS_LIB"standard"
BOM_COST"IO_SLOT"
BODY_TYPE"PLUMBING"
HDL_TAP"TRUE"
ROOM"RISER1";
"B \NAC \NWC"3;
"S \NAC"
BN"6"18;
%"TAP"
"6","(-4350,5175)","2","standard","I93";
;
CDS_LIB"standard"
BOM_COST"IO_SLOT"
BODY_TYPE"PLUMBING"
HDL_TAP"TRUE"
ROOM"RISER1";
"B \NAC \NWC"3;
"S \NAC"
BN"5"20;
%"TAP"
"6","(-4350,5275)","2","standard","I94";
;
CDS_LIB"standard"
BOM_COST"IO_SLOT"
BODY_TYPE"PLUMBING"
HDL_TAP"TRUE"
ROOM"RISER1";
"B \NAC \NWC"3;
"S \NAC"
BN"4"22;
%"TAP"
"6","(-4350,5375)","2","standard","I95";
;
CDS_LIB"standard"
BOM_COST"IO_SLOT"
BODY_TYPE"PLUMBING"
HDL_TAP"TRUE"
ROOM"RISER1";
"B \NAC \NWC"3;
"S \NAC"
BN"3"24;
%"TAP"
"6","(-4350,5475)","2","standard","I96";
;
CDS_LIB"standard"
BOM_COST"IO_SLOT"
BODY_TYPE"PLUMBING"
HDL_TAP"TRUE"
ROOM"RISER1";
"B \NAC \NWC"3;
"S \NAC"
BN"2"47;
%"TAP"
"6","(-4350,5575)","2","standard","I97";
;
CDS_LIB"standard"
BOM_COST"IO_SLOT"
BODY_TYPE"PLUMBING"
HDL_TAP"TRUE"
ROOM"RISER1";
"B \NAC \NWC"3;
"S \NAC"
BN"1"48;
%"TAP"
"6","(-4350,5675)","2","standard","I98";
;
CDS_LIB"standard"
BOM_COST"IO_SLOT"
BODY_TYPE"PLUMBING"
HDL_TAP"TRUE"
ROOM"RISER1";
"B \NAC \NWC"3;
"S \NAC"
BN"0"49;
END.
